(kicad_pcb
	(version 20260206)
	(generator "pcbnew")
	(generator_version "10.0")
	(general
		(thickness 1.6)
		(legacy_teardrops no)
	)
	(paper "A4")
	(title_block
		(title "panther-plus-userver — 13130-1b_20150205.brd")
		(comment 1 "Honey Badger (Wiwynn) / footprints 1374-1378 of 1509")
	)
	(layers
		(0 "F.Cu" signal "TOP")
		(4 "In1.Cu" signal "L2")
		(6 "In2.Cu" signal "L3")
		(8 "In3.Cu" signal "L4")
		(10 "In4.Cu" signal "L5")
		(12 "In5.Cu" signal "L6")
		(14 "In6.Cu" signal "L7")
		(16 "In7.Cu" signal "L8")
		(18 "In8.Cu" signal "L9")
		(20 "In9.Cu" signal "L10")
		(22 "In10.Cu" signal "L11")
		(2 "B.Cu" signal "BOTTOM")
		(9 "F.Adhes" user "F.Adhesive")
		(11 "B.Adhes" user "B.Adhesive")
		(13 "F.Paste" user "Package Geometry/Pastemask Top")
		(15 "B.Paste" user "Package Geometry/Pastemask Bottom")
		(5 "F.SilkS" user "Ref Des/Silkscreen Top")
		(7 "B.SilkS" user "Ref Des/Silkscreen Bottom")
		(1 "F.Mask" user "Board Geometry/Soldermask Top")
		(3 "B.Mask" user "Board Geometry/Soldermask Bottom")
		(17 "Dwgs.User" user "User.Drawings")
		(19 "Cmts.User" user "User.Comments")
		(21 "Eco1.User" user "User.Eco1")
		(23 "Eco2.User" user "User.Eco2")
		(25 "Edge.Cuts" user "Board Geometry/Outline")
		(27 "Margin" user)
		(31 "F.CrtYd" user "Package Geometry/Place Bound Top")
		(29 "B.CrtYd" user "Package Geometry/Place Bound Bottom")
		(35 "F.Fab" user "Ref Des/Assembly Top")
		(33 "B.Fab" user "Ref Des/Assembly Bottom")
	)
	(footprint ""
		(layer "B.Cu")
		(at 102.073964 -41.529 180)
		(property "Reference" "C174"
			(at 0 0 0)
			(layer "B.SilkS")
			(hide yes)
			(effects
				(font
					(size 1.27 1.27)
				)
				(justify mirror)
			)
		)
		(property "Value" "SC1U10V2KX-1GP"
			(at -1.1811 -2.7051 180)
			(unlocked yes)
			(layer "B.Fab")
			(hide yes)
			(effects
				(font
					(size 1.016 1.016)
					(thickness 0.1524)
				)
				(justify mirror)
			)
		)
		(property "Device Type" "C402H22"
			(at -1.1811 -4.2291 180)
			(unlocked yes)
			(layer "B.Fab")
			(hide yes)
			(effects
				(font
					(size 1.016 1.016)
					(thickness 0.1524)
				)
				(justify mirror)
			)
		)
		(duplicate_pad_numbers_are_jumpers no)
		(fp_rect
			(start 0.381 0.7366)
			(end -0.381 -0.7366)
			(stroke
				(width 0)
				(type default)
			)
			(fill no)
			(layer "B.CrtYd")
		)
		(fp_rect
			(start 0.381 0.7366)
			(end -0.381 -0.7366)
			(stroke
				(width 0)
				(type default)
			)
			(fill no)
			(layer "B.Fab")
		)
		(pad "1" smd custom
			(at 0 -0.4572)
			(size 0.1143 0.1143)
			(layers "B.Cu" "B.Mask" "B.Paste")
			(net "PVCCP")
			(options
				(clearance outline)
				(anchor circle)
			)
			(primitives
				(gr_poly
					(pts
						(arc
							(start -0.254 0.1778)
							(mid -0.239121 0.213721)
							(end -0.2032 0.2286)
						)
						(arc
							(start 0.2032 0.2286)
							(mid 0.239121 0.213721)
							(end 0.254 0.1778)
						)
						(arc
							(start 0.254 -0.1778)
							(mid 0.239121 -0.213721)
							(end 0.2032 -0.2286)
						)
						(arc
							(start -0.2032 -0.2286)
							(mid -0.239121 -0.213721)
							(end -0.254 -0.1778)
						)
					)
					(width 0)
					(fill yes)
				)
			)
		)
		(pad "2" smd custom
			(at 0 0.4572)
			(size 0.1143 0.1143)
			(layers "B.Cu" "B.Mask" "B.Paste")
			(net "GND")
			(options
				(clearance outline)
				(anchor circle)
			)
			(primitives
				(gr_poly
					(pts
						(arc
							(start -0.254 0.1778)
							(mid -0.239121 0.213721)
							(end -0.2032 0.2286)
						)
						(arc
							(start 0.2032 0.2286)
							(mid 0.239121 0.213721)
							(end 0.254 0.1778)
						)
						(arc
							(start 0.254 -0.1778)
							(mid 0.239121 -0.213721)
							(end 0.2032 -0.2286)
						)
						(arc
							(start -0.2032 -0.2286)
							(mid -0.239121 -0.213721)
							(end -0.254 -0.1778)
						)
					)
					(width 0)
					(fill yes)
				)
			)
		)
	)
	(footprint ""
		(layer "B.Cu")
		(at 104.521 -33.401 180)
		(property "Reference" "C222"
			(at 0 0 0)
			(layer "B.SilkS")
			(hide yes)
			(effects
				(font
					(size 1.27 1.27)
				)
				(justify mirror)
			)
		)
		(property "Value" "SC33P50V2JN-3GP"
			(at -1.1811 -2.7051 180)
			(unlocked yes)
			(layer "B.Fab")
			(hide yes)
			(effects
				(font
					(size 1.016 1.016)
					(thickness 0.1524)
				)
				(justify mirror)
			)
		)
		(property "Device Type" "C402H22"
			(at -1.1811 -4.2291 180)
			(unlocked yes)
			(layer "B.Fab")
			(hide yes)
			(effects
				(font
					(size 1.016 1.016)
					(thickness 0.1524)
				)
				(justify mirror)
			)
		)
		(duplicate_pad_numbers_are_jumpers no)
		(fp_rect
			(start 0.381 0.7366)
			(end -0.381 -0.7366)
			(stroke
				(width 0)
				(type default)
			)
			(fill no)
			(layer "B.CrtYd")
		)
		(fp_rect
			(start 0.381 0.7366)
			(end -0.381 -0.7366)
			(stroke
				(width 0)
				(type default)
			)
			(fill no)
			(layer "B.Fab")
		)
		(pad "1" smd custom
			(at 0 -0.4572)
			(size 0.1143 0.1143)
			(layers "B.Cu" "B.Mask" "B.Paste")
			(net "PWRGD_DDR3_VCCA")
			(options
				(clearance outline)
				(anchor circle)
			)
			(primitives
				(gr_poly
					(pts
						(arc
							(start -0.254 0.1778)
							(mid -0.239121 0.213721)
							(end -0.2032 0.2286)
						)
						(arc
							(start 0.2032 0.2286)
							(mid 0.239121 0.213721)
							(end 0.254 0.1778)
						)
						(arc
							(start 0.254 -0.1778)
							(mid 0.239121 -0.213721)
							(end 0.2032 -0.2286)
						)
						(arc
							(start -0.2032 -0.2286)
							(mid -0.239121 -0.213721)
							(end -0.254 -0.1778)
						)
					)
					(width 0)
					(fill yes)
				)
			)
		)
		(pad "2" smd custom
			(at 0 0.4572)
			(size 0.1143 0.1143)
			(layers "B.Cu" "B.Mask" "B.Paste")
			(net "GND")
			(options
				(clearance outline)
				(anchor circle)
			)
			(primitives
				(gr_poly
					(pts
						(arc
							(start -0.254 0.1778)
							(mid -0.239121 0.213721)
							(end -0.2032 0.2286)
						)
						(arc
							(start 0.2032 0.2286)
							(mid 0.239121 0.213721)
							(end 0.254 0.1778)
						)
						(arc
							(start 0.254 -0.1778)
							(mid 0.239121 -0.213721)
							(end 0.2032 -0.2286)
						)
						(arc
							(start -0.2032 -0.2286)
							(mid -0.239121 -0.213721)
							(end -0.254 -0.1778)
						)
					)
					(width 0)
					(fill yes)
				)
			)
		)
	)
	(footprint ""
		(layer "B.Cu")
		(at 53.086 -12.7 180)
		(property "Reference" "R413"
			(at 0 0 0)
			(layer "B.SilkS")
			(hide yes)
			(effects
				(font
					(size 1.27 1.27)
				)
				(justify mirror)
			)
		)
		(property "Value" "0R2J-2-GP"
			(at -1.7907 -1.1176 180)
			(unlocked yes)
			(layer "B.Fab")
			(hide yes)
			(effects
				(font
					(size 1.016 1.016)
					(thickness 0.1524)
				)
				(justify mirror)
			)
		)
		(property "Device Type" "R402H16"
			(at -1.7907 -2.6416 180)
			(unlocked yes)
			(layer "B.Fab")
			(hide yes)
			(effects
				(font
					(size 1.016 1.016)
					(thickness 0.1524)
				)
				(justify mirror)
			)
		)
		(duplicate_pad_numbers_are_jumpers no)
		(fp_rect
			(start 0.381 0.8382)
			(end -0.381 -0.8382)
			(stroke
				(width 0)
				(type default)
			)
			(fill no)
			(layer "B.CrtYd")
		)
		(fp_rect
			(start 0.381 0.8382)
			(end -0.381 -0.8382)
			(stroke
				(width 0)
				(type default)
			)
			(fill no)
			(layer "B.Fab")
		)
		(pad "1" smd custom
			(at 0 -0.4318)
			(size 0.127 0.127)
			(layers "B.Cu" "B.Mask" "B.Paste")
			(net "GBE_R_SMDATA")
			(options
				(clearance outline)
				(anchor circle)
			)
			(primitives
				(gr_poly
					(pts
						(arc
							(start -0.2032 0.2794)
							(mid -0.239121 0.264521)
							(end -0.254 0.2286)
						)
						(arc
							(start -0.254 -0.2286)
							(mid -0.239121 -0.264521)
							(end -0.2032 -0.2794)
						)
						(arc
							(start 0.2032 -0.2794)
							(mid 0.239121 -0.264521)
							(end 0.254 -0.2286)
						)
						(arc
							(start 0.254 0.2286)
							(mid 0.239121 0.264521)
							(end 0.2032 0.2794)
						)
					)
					(width 0)
					(fill yes)
				)
			)
		)
		(pad "2" smd custom
			(at 0 0.4318)
			(size 0.127 0.127)
			(layers "B.Cu" "B.Mask" "B.Paste")
			(net "GF_GBE_SMBDATA")
			(options
				(clearance outline)
				(anchor circle)
			)
			(primitives
				(gr_poly
					(pts
						(arc
							(start -0.2032 0.2794)
							(mid -0.239121 0.264521)
							(end -0.254 0.2286)
						)
						(arc
							(start -0.254 -0.2286)
							(mid -0.239121 -0.264521)
							(end -0.2032 -0.2794)
						)
						(arc
							(start 0.2032 -0.2794)
							(mid 0.239121 -0.264521)
							(end 0.254 -0.2286)
						)
						(arc
							(start 0.254 0.2286)
							(mid 0.239121 0.264521)
							(end 0.2032 0.2794)
						)
					)
					(width 0)
					(fill yes)
				)
			)
		)
	)
	(footprint ""
		(layer "B.Cu")
		(at 161.671 -72.39 90)
		(property "Reference" "R233"
			(at 0 0 90)
			(layer "B.SilkS")
			(hide yes)
			(effects
				(font
					(size 1.27 1.27)
				)
				(justify mirror)
			)
		)
		(property "Value" "100R2F-L1-GP-U"
			(at -0.064008 -3.993896 90)
			(unlocked yes)
			(layer "B.Fab")
			(hide yes)
			(effects
				(font
					(size 1.016 1.016)
					(thickness 0.1524)
				)
				(justify mirror)
			)
		)
		(property "Device Type" "R402H14"
			(at -0.064008 -5.517896 90)
			(unlocked yes)
			(layer "B.Fab")
			(hide yes)
			(effects
				(font
					(size 1.016 1.016)
					(thickness 0.1524)
				)
				(justify mirror)
			)
		)
		(duplicate_pad_numbers_are_jumpers no)
		(fp_rect
			(start 0.381 0.8382)
			(end -0.381 -0.8382)
			(stroke
				(width 0)
				(type default)
			)
			(fill no)
			(layer "B.CrtYd")
		)
		(fp_rect
			(start 0.381 0.8382)
			(end -0.381 -0.8382)
			(stroke
				(width 0)
				(type default)
			)
			(fill no)
			(layer "B.Fab")
		)
		(pad "1" smd custom
			(at 0 -0.4318 270)
			(size 0.127 0.127)
			(layers "B.Cu" "B.Mask" "B.Paste")
			(net "PV_VDDR")
			(options
				(clearance outline)
				(anchor circle)
			)
			(primitives
				(gr_poly
					(pts
						(arc
							(start -0.2032 0.2794)
							(mid -0.239121 0.264521)
							(end -0.254 0.2286)
						)
						(arc
							(start -0.254 -0.2286)
							(mid -0.239121 -0.264521)
							(end -0.2032 -0.2794)
						)
						(arc
							(start 0.2032 -0.2794)
							(mid 0.239121 -0.264521)
							(end 0.254 -0.2286)
						)
						(arc
							(start 0.254 0.2286)
							(mid 0.239121 0.264521)
							(end 0.2032 0.2794)
						)
					)
					(width 0)
					(fill yes)
				)
			)
		)
		(pad "2" smd custom
			(at 0 0.4318 270)
			(size 0.127 0.127)
			(layers "B.Cu" "B.Mask" "B.Paste")
			(net "DDR3_M_A_VREF_CA")
			(options
				(clearance outline)
				(anchor circle)
			)
			(primitives
				(gr_poly
					(pts
						(arc
							(start -0.2032 0.2794)
							(mid -0.239121 0.264521)
							(end -0.254 0.2286)
						)
						(arc
							(start -0.254 -0.2286)
							(mid -0.239121 -0.264521)
							(end -0.2032 -0.2794)
						)
						(arc
							(start 0.2032 -0.2794)
							(mid 0.239121 -0.264521)
							(end 0.254 -0.2286)
						)
						(arc
							(start 0.254 0.2286)
							(mid 0.239121 0.264521)
							(end 0.2032 0.2794)
						)
					)
					(width 0)
					(fill yes)
				)
			)
		)
	)
	(footprint ""
		(layer "B.Cu")
		(at 96.52 -65.659 180)
		(property "Reference" "PU1"
			(at 0 0 0)
			(layer "B.SilkS")
			(hide yes)
			(effects
				(font
					(size 1.27 1.27)
				)
				(justify mirror)
			)
		)
		(property "Value" "EN6337QI-GP-U"
			(at 3.6576 -5.2832 180)
			(unlocked yes)
			(layer "B.Fab")
			(hide yes)
			(effects
				(font
					(size 1.016 1.016)
					(thickness 0.1524)
				)
				(justify mirror)
			)
		)
		(property "Device Type" "QFN38G4070-G260193-UH75"
			(at 3.6576 -6.8072 180)
			(unlocked yes)
			(layer "B.Fab")
			(hide yes)
			(effects
				(font
					(size 1.016 1.016)
					(thickness 0.1524)
				)
				(justify mirror)
			)
		)
		(duplicate_pad_numbers_are_jumpers no)
		(fp_poly
			(pts
				(xy -2.263902 -3.89636) (xy -2.898902 -4.53136) (xy -1.628902 -4.53136)
			)
			(stroke
				(width 0)
				(type default)
			)
			(fill yes)
			(layer "B.SilkS")
		)
		(fp_rect
			(start 2.3876 3.8862)
			(end -2.3876 -3.8862)
			(stroke
				(width 0)
				(type default)
			)
			(fill no)
			(layer "B.CrtYd")
		)
		(fp_rect
			(start 2.3876 3.8862)
			(end -2.3876 -3.8862)
			(stroke
				(width 0)
				(type default)
			)
			(fill no)
			(layer "B.Fab")
		)
		(pad "1" smd rect
			(at -1.249934 -3.42392)
			(size 0.3048 0.6604)
			(layers "B.Cu" "B.Mask" "B.Paste")
			(net "Net_411")
		)
		(pad "2" smd rect
			(at -0.750062 -3.42392)
			(size 0.3048 0.6604)
			(layers "B.Cu" "B.Mask" "B.Paste")
			(net "Net_417")
		)
		(pad "3" smd rect
			(at -0.249936 -3.42392)
			(size 0.3048 0.6604)
			(layers "B.Cu" "B.Mask" "B.Paste")
			(net "Net_416")
		)
		(pad "4" smd rect
			(at 0.249936 -3.42392)
			(size 0.3048 0.6604)
			(layers "B.Cu" "B.Mask" "B.Paste")
			(net "Net_419")
		)
		(pad "5" smd rect
			(at 0.750062 -3.42392)
			(size 0.3048 0.6604)
			(layers "B.Cu" "B.Mask" "B.Paste")
			(net "P1V1")
		)
		(pad "6" smd rect
			(at 1.249934 -3.42392)
			(size 0.3048 0.6604)
			(layers "B.Cu" "B.Mask" "B.Paste")
			(net "P1V1")
		)
		(pad "7" smd rect
			(at 1.923796 -2.999994)
			(size 0.635 0.3048)
			(drill
				(offset -0.0127 0)
			)
			(layers "B.Cu" "B.Mask" "B.Paste")
			(net "P1V1")
		)
		(pad "8" smd rect
			(at 1.923796 -2.500122)
			(size 0.6604 0.3048)
			(layers "B.Cu" "B.Mask" "B.Paste")
			(net "P1V1")
		)
		(pad "9" smd rect
			(at 1.923796 -1.999996)
			(size 0.6604 0.3048)
			(layers "B.Cu" "B.Mask" "B.Paste")
			(net "P1V1")
		)
		(pad "10" smd rect
			(at 1.923796 -1.500124)
			(size 0.6604 0.3048)
			(layers "B.Cu" "B.Mask" "B.Paste")
			(net "P1V1")
		)
		(pad "11" smd rect
			(at 1.923796 -0.999998)
			(size 0.6604 0.3048)
			(layers "B.Cu" "B.Mask" "B.Paste")
			(net "P1V1")
		)
		(pad "12" smd rect
			(at 1.923796 -0.500126)
			(size 0.6604 0.3048)
			(layers "B.Cu" "B.Mask" "B.Paste")
			(net "Net_418")
		)
		(pad "13" smd rect
			(at 1.923796 0)
			(size 0.6604 0.3048)
			(layers "B.Cu" "B.Mask" "B.Paste")
			(net "GND")
		)
		(pad "14" smd rect
			(at 1.923796 0.500126)
			(size 0.6604 0.3048)
			(layers "B.Cu" "B.Mask" "B.Paste")
			(net "GND")
		)
		(pad "15" smd rect
			(at 1.923796 0.999998)
			(size 0.6604 0.3048)
			(layers "B.Cu" "B.Mask" "B.Paste")
			(net "GND")
		)
		(pad "16" smd rect
			(at 1.923796 1.500124)
			(size 0.6604 0.3048)
			(layers "B.Cu" "B.Mask" "B.Paste")
			(net "GND")
		)
		(pad "17" smd rect
			(at 1.923796 1.999996)
			(size 0.6604 0.3048)
			(layers "B.Cu" "B.Mask" "B.Paste")
			(net "GND")
		)
		(pad "18" smd rect
			(at 1.923796 2.500122)
			(size 0.6604 0.3048)
			(layers "B.Cu" "B.Mask" "B.Paste")
			(net "GND")
		)
		(pad "19" smd rect
			(at 1.923796 2.999994)
			(size 0.635 0.3048)
			(drill
				(offset -0.0127 0)
			)
			(layers "B.Cu" "B.Mask" "B.Paste")
			(net "VR_P1V1_PVIN")
		)
		(pad "20" smd rect
			(at 1.249934 3.42392)
			(size 0.3048 0.6604)
			(layers "B.Cu" "B.Mask" "B.Paste")
			(net "VR_P1V1_PVIN")
		)
		(pad "21" smd rect
			(at 0.750062 3.42392)
			(size 0.3048 0.6604)
			(layers "B.Cu" "B.Mask" "B.Paste")
			(net "VR_P1V1_PVIN")
		)
		(pad "22" smd rect
			(at 0.249936 3.42392)
			(size 0.3048 0.6604)
			(layers "B.Cu" "B.Mask" "B.Paste")
			(net "Net_421")
		)
		(pad "23" smd rect
			(at -0.249936 3.42392)
			(size 0.3048 0.6604)
			(layers "B.Cu" "B.Mask" "B.Paste")
			(net "Net_420")
		)
		(pad "24" smd rect
			(at -0.750062 3.42392)
			(size 0.3048 0.6604)
			(layers "B.Cu" "B.Mask" "B.Paste")
			(net "TP_VDDB")
		)
		(pad "25" smd rect
			(at -1.249934 3.42392)
			(size 0.3048 0.6604)
			(layers "B.Cu" "B.Mask" "B.Paste")
			(net "TP_BGND")
		)
		(pad "26" smd rect
			(at -1.923796 2.999994)
			(size 0.635 0.3048)
			(drill
				(offset 0.0127 0)
			)
			(layers "B.Cu" "B.Mask" "B.Paste")
			(net "GND")
		)
		(pad "27" smd rect
			(at -1.923796 2.500122)
			(size 0.6604 0.3048)
			(layers "B.Cu" "B.Mask" "B.Paste")
			(net "VR_P1V1_EN")
		)
		(pad "28" smd rect
			(at -1.923796 1.999996)
			(size 0.6604 0.3048)
			(layers "B.Cu" "B.Mask" "B.Paste")
			(net "PWRGD_P1V1_PG")
		)
		(pad "29" smd rect
			(at -1.923796 1.500124)
			(size 0.6604 0.3048)
			(layers "B.Cu" "B.Mask" "B.Paste")
			(net "Net_90")
		)
		(pad "30" smd rect
			(at -1.923796 0.999998)
			(size 0.6604 0.3048)
			(layers "B.Cu" "B.Mask" "B.Paste")
			(net "VR_P1V1_SS")
		)
		(pad "31" smd rect
			(at -1.923796 0.500126)
			(size 0.6604 0.3048)
			(layers "B.Cu" "B.Mask" "B.Paste")
			(net "VR_P1V1_VFB")
		)
		(pad "32" smd rect
			(at -1.923796 0)
			(size 0.6604 0.3048)
			(layers "B.Cu" "B.Mask" "B.Paste")
			(net "AGND_P1V1")
		)
		(pad "33" smd rect
			(at -1.923796 -0.500126)
			(size 0.6604 0.3048)
			(layers "B.Cu" "B.Mask" "B.Paste")
			(net "VR_P1V1_AVIN")
		)
		(pad "34" smd rect
			(at -1.923796 -0.999998)
			(size 0.6604 0.3048)
			(layers "B.Cu" "B.Mask" "B.Paste")
			(net "Net_415")
		)
		(pad "35" smd rect
			(at -1.923796 -1.500124)
			(size 0.6604 0.3048)
			(layers "B.Cu" "B.Mask" "B.Paste")
			(net "Net_414")
		)
		(pad "36" smd rect
			(at -1.923796 -1.999996)
			(size 0.6604 0.3048)
			(layers "B.Cu" "B.Mask" "B.Paste")
			(net "Net_413")
		)
		(pad "37" smd rect
			(at -1.923796 -2.500122)
			(size 0.6604 0.3048)
			(layers "B.Cu" "B.Mask" "B.Paste")
			(net "Net_412")
		)
		(pad "38" smd rect
			(at -1.923796 -2.999994)
			(size 0.635 0.3048)
			(drill
				(offset 0.0127 0)
			)
			(layers "B.Cu" "B.Mask" "B.Paste")
			(net "Net_410")
		)
		(pad "39" smd rect
			(at 0 1.260094)
			(size 2.5908 1.9304)
			(layers "B.Cu" "B.Mask" "B.Paste")
			(net "GND")
		)
		(zone
			(layer "B.Cu")
			(hatch none 0.5)
			(connect_pads
				(clearance 0)
			)
			(min_thickness 0.25)
			(keepout
				(tracks allowed)
				(vias not_allowed)
				(pads allowed)
				(copperpour not_allowed)
				(footprints allowed)
			)
			(placement
				(enabled no)
				(sheetname "")
			)
			(fill
				(thermal_gap 0.5)
				(thermal_bridge_width 0.5)
				(island_removal_mode 0)
			)
			(polygon
				(pts
					(xy 94.926404 -68.75272) (xy 94.926404 -67.884294) (xy 97.8154 -67.884294) (xy 97.8154 -65.953894)
					(xy 94.926404 -65.953894) (xy 94.926404 -62.56528) (xy 98.113596 -62.56528) (xy 98.113596 -68.75272)
				)
			)
		)
		(zone
			(layer "B.Cu")
			(hatch none 0.5)
			(connect_pads
				(clearance 0)
			)
			(min_thickness 0.25)
			(keepout
				(tracks not_allowed)
				(vias allowed)
				(pads allowed)
				(copperpour not_allowed)
				(footprints allowed)
			)
			(placement
				(enabled no)
				(sheetname "")
			)
			(fill
				(thermal_gap 0.5)
				(thermal_bridge_width 0.5)
				(island_removal_mode 0)
			)
			(polygon
				(pts
					(xy 94.926404 -68.75272) (xy 94.926404 -67.884294) (xy 97.8154 -67.884294) (xy 97.8154 -65.953894)
					(xy 94.926404 -65.953894) (xy 94.926404 -62.56528) (xy 98.113596 -62.56528) (xy 98.113596 -68.75272)
				)
			)
		)
	)
)
